# T6G (Grand Teton) — schematic netlist excerpt (pin names and nets, part order shuffled) for the footprints in the layout excerpt that follows; sources: Cadence DE-HDL packaged netlist, KiCad conversion of 04192023_DAF0TMB3IC0_F0TG_MB_C_brd_V02_OCP.brd

PR3855  Q_RES  71.5K 1% CHIP  pkg 0402LF  page 141 : A = P3V3_OCP_MODE_2 ; B = GND
R1488  Q_RES  4.7K 5% EMPTY  pkg 0201LF  page 342 : A = P1V8_CPU1_RT_1D ; B = JTAG_TDI_RT_CPU1_P2
C1871  Q_CAP  0.1UF 25V 10% X7R  pkg 0402  page 113 : A = P2E_MB_BMC_TX_BUF_DN<0> ; B = P2E_MB_BMC_TX_BUF_C_DN<0>

(kicad_pcb
	(version 20260206)
	(generator "pcbnew")
	(generator_version "10.0")
	(general
		(thickness 1.6)
		(legacy_teardrops no)
	)
	(paper "A4")
	(title_block
		(title "04192023_DAF0TMB3IC0_F0TG_MB_C_brd_V02_OCP.brd")
		(comment 1 "Grand Teton / footprints 4331-4333 of 8354")
	)
	(layers
		(0 "F.Cu" signal "TOP")
		(4 "In1.Cu" signal "GND")
		(6 "In2.Cu" signal "IN1")
		(8 "In3.Cu" signal "GND1")
		(10 "In4.Cu" signal "IN2")
		(12 "In5.Cu" signal "GND2")
		(14 "In6.Cu" signal "IN3")
		(16 "In7.Cu" signal "GND3")
		(18 "In8.Cu" signal "VCC")
		(20 "In9.Cu" signal "VCC1")
		(22 "In10.Cu" signal "GND4")
		(24 "In11.Cu" signal "IN4")
		(26 "In12.Cu" signal "GND5")
		(28 "In13.Cu" signal "IN5")
		(30 "In14.Cu" signal "GND6")
		(32 "In15.Cu" signal "IN6")
		(34 "In16.Cu" signal "GND7")
		(2 "B.Cu" signal "BOTTOM")
		(9 "F.Adhes" user "F.Adhesive")
		(11 "B.Adhes" user "B.Adhesive")
		(13 "F.Paste" user "Package Geometry/Pastemask Top")
		(15 "B.Paste" user "Package Geometry/Pastemask Bottom")
		(5 "F.SilkS" user "Ref Des/Silkscreen Top")
		(7 "B.SilkS" user "Ref Des/Silkscreen Bottom")
		(1 "F.Mask" user "Board Geometry/Soldermask Top")
		(3 "B.Mask" user "Board Geometry/Soldermask Bottom")
		(17 "Dwgs.User" user "User.Drawings")
		(19 "Cmts.User" user "User.Comments")
		(21 "Eco1.User" user "User.Eco1")
		(23 "Eco2.User" user "User.Eco2")
		(25 "Edge.Cuts" user "Board Geometry/Outline")
		(27 "Margin" user)
		(31 "F.CrtYd" user "Package Geometry/Place Bound Top")
		(29 "B.CrtYd" user "Package Geometry/Place Bound Bottom")
		(35 "F.Fab" user "Ref Des/Assembly Top")
		(33 "B.Fab" user "Ref Des/Assembly Bottom")
	)
	(footprint ""
		(layer "F.Cu")
		(at 28.53563 -422.330626 180)
		(property "Reference" "C1871"
			(at 0 0 180)
			(layer "F.SilkS")
			(hide yes)
			(effects
				(font
					(size 1.27 1.27)
				)
			)
		)
		(property "Value" ""
			(at 0 0 180)
			(layer "F.Fab")
			(effects
				(font
					(size 1.27 1.27)
				)
			)
		)
		(duplicate_pad_numbers_are_jumpers no)
		(fp_line
			(start 0.7874 0.4064)
			(end -0.7874 0.4064)
			(stroke
				(width 0.1524)
				(type default)
			)
			(layer "F.SilkS")
		)
		(fp_line
			(start 0.7874 -0.284226)
			(end 0.7874 0.4064)
			(stroke
				(width 0.1524)
				(type default)
			)
			(layer "F.SilkS")
		)
		(fp_line
			(start -0.7874 -0.4064)
			(end -0.34417 -0.4064)
			(stroke
				(width 0.1524)
				(type default)
			)
			(layer "F.SilkS")
		)
		(fp_line
			(start 0.6858 0.3048)
			(end 0.1016 0.3048)
			(stroke
				(width 0.1)
				(type default)
			)
			(layer "F.Fab")
		)
		(fp_line
			(start 0.6858 -0.3048)
			(end 0.6858 0.3048)
			(stroke
				(width 0.1)
				(type default)
			)
			(layer "F.Fab")
		)
		(fp_line
			(start 0.1016 0.3048)
			(end 0.1016 0.2794)
			(stroke
				(width 0.1)
				(type default)
			)
			(layer "F.Fab")
		)
		(fp_line
			(start 0.1016 0.2794)
			(end -0.1016 0.2794)
			(stroke
				(width 0.1)
				(type default)
			)
			(layer "F.Fab")
		)
		(fp_line
			(start 0.1016 -0.2794)
			(end 0.1016 -0.3048)
			(stroke
				(width 0.1)
				(type default)
			)
			(layer "F.Fab")
		)
		(fp_line
			(start 0.1016 -0.3048)
			(end 0.6858 -0.3048)
			(stroke
				(width 0.1)
				(type default)
			)
			(layer "F.Fab")
		)
		(fp_line
			(start -0.1016 0.3048)
			(end -0.6858 0.3048)
			(stroke
				(width 0.1)
				(type default)
			)
			(layer "F.Fab")
		)
		(fp_line
			(start -0.1016 0.2794)
			(end -0.1016 0.3048)
			(stroke
				(width 0.1)
				(type default)
			)
			(layer "F.Fab")
		)
		(fp_line
			(start -0.1016 -0.2794)
			(end 0.1016 -0.2794)
			(stroke
				(width 0.1)
				(type default)
			)
			(layer "F.Fab")
		)
		(fp_line
			(start -0.1016 -0.3048)
			(end -0.1016 -0.2794)
			(stroke
				(width 0.1)
				(type default)
			)
			(layer "F.Fab")
		)
		(fp_line
			(start -0.6858 0.3048)
			(end -0.6858 -0.3048)
			(stroke
				(width 0.1)
				(type default)
			)
			(layer "F.Fab")
		)
		(fp_line
			(start -0.6858 -0.3048)
			(end -0.1016 -0.3048)
			(stroke
				(width 0.1)
				(type default)
			)
			(layer "F.Fab")
		)
		(pad "1" smd rect
			(at -0.40005 0)
			(size 0.4572 0.508)
			(layers "F.Cu" "F.Mask" "F.Paste")
			(net "P2E_MB_BMC_TX_BUF_DN<0>")
		)
		(pad "2" smd rect
			(at 0.40005 0)
			(size 0.4572 0.508)
			(layers "F.Cu" "F.Mask" "F.Paste")
			(net "P2E_MB_BMC_TX_BUF_C_DN<0>")
		)
	)
	(footprint ""
		(layer "F.Cu")
		(at 177.81016 -393.2936)
		(property "Reference" "R1488"
			(at 0 0 0)
			(layer "F.SilkS")
			(hide yes)
			(effects
				(font
					(size 1.27 1.27)
				)
			)
		)
		(property "Value" ""
			(at 0 0 0)
			(layer "F.Fab")
			(effects
				(font
					(size 1.27 1.27)
				)
			)
		)
		(duplicate_pad_numbers_are_jumpers no)
		(fp_line
			(start -0.32512 -0.175006)
			(end 0.32512 -0.175006)
			(stroke
				(width 0.1)
				(type default)
			)
			(layer "F.Fab")
		)
		(fp_line
			(start -0.32512 0.175006)
			(end -0.32512 -0.175006)
			(stroke
				(width 0.1)
				(type default)
			)
			(layer "F.Fab")
		)
		(fp_line
			(start 0.32512 -0.175006)
			(end 0.32512 0.175006)
			(stroke
				(width 0.1)
				(type default)
			)
			(layer "F.Fab")
		)
		(fp_line
			(start 0.32512 0.175006)
			(end -0.32512 0.175006)
			(stroke
				(width 0.1)
				(type default)
			)
			(layer "F.Fab")
		)
		(pad "1" smd rect
			(at -0.2667 0)
			(size 0.3048 0.381)
			(layers "F.Cu" "F.Mask" "F.Paste")
			(net "P1V8_CPU1_RT_1D")
		)
		(pad "2" smd rect
			(at 0.2667 0 180)
			(size 0.3048 0.381)
			(layers "F.Cu" "F.Mask" "F.Paste")
			(net "JTAG_TDI_RT_CPU1_P2")
		)
	)
	(footprint ""
		(layer "F.Cu")
		(at 89.562432 -70.69582 -90)
		(property "Reference" "PR3855"
			(at 0 0 270)
			(layer "F.SilkS")
			(hide yes)
			(effects
				(font
					(size 1.27 1.27)
				)
			)
		)
		(property "Value" ""
			(at 0 0 270)
			(layer "F.Fab")
			(effects
				(font
					(size 1.27 1.27)
				)
			)
		)
		(duplicate_pad_numbers_are_jumpers no)
		(fp_line
			(start -0.7874 0.4064)
			(end -0.7874 -0.4064)
			(stroke
				(width 0.1524)
				(type default)
			)
			(layer "F.SilkS")
		)
		(fp_line
			(start 0.7874 0.4064)
			(end -0.7874 0.4064)
			(stroke
				(width 0.1524)
				(type default)
			)
			(layer "F.SilkS")
		)
		(fp_line
			(start -0.7874 -0.4064)
			(end 0.7874 -0.4064)
			(stroke
				(width 0.1524)
				(type default)
			)
			(layer "F.SilkS")
		)
		(fp_line
			(start 0.7874 -0.4064)
			(end 0.7874 0.4064)
			(stroke
				(width 0.1524)
				(type default)
			)
			(layer "F.SilkS")
		)
		(fp_line
			(start -0.67945 0.3048)
			(end -0.67945 -0.305054)
			(stroke
				(width 0.1)
				(type default)
			)
			(layer "F.Fab")
		)
		(fp_line
			(start -0.12065 0.3048)
			(end -0.67945 0.3048)
			(stroke
				(width 0.1)
				(type default)
			)
			(layer "F.Fab")
		)
		(fp_line
			(start 0.120396 0.3048)
			(end 0.120396 0.2794)
			(stroke
				(width 0.1)
				(type default)
			)
			(layer "F.Fab")
		)
		(fp_line
			(start 0.67945 0.3048)
			(end 0.120396 0.3048)
			(stroke
				(width 0.1)
				(type default)
			)
			(layer "F.Fab")
		)
		(fp_line
			(start -0.12065 0.2794)
			(end -0.12065 0.3048)
			(stroke
				(width 0.1)
				(type default)
			)
			(layer "F.Fab")
		)
		(fp_line
			(start 0.120396 0.2794)
			(end -0.12065 0.2794)
			(stroke
				(width 0.1)
				(type default)
			)
			(layer "F.Fab")
		)
		(fp_line
			(start -0.12065 -0.2794)
			(end 0.12065 -0.2794)
			(stroke
				(width 0.1)
				(type default)
			)
			(layer "F.Fab")
		)
		(fp_line
			(start 0.12065 -0.2794)
			(end 0.12065 -0.3048)
			(stroke
				(width 0.1)
				(type default)
			)
			(layer "F.Fab")
		)
		(fp_line
			(start 0.12065 -0.3048)
			(end 0.67945 -0.3048)
			(stroke
				(width 0.1)
				(type default)
			)
			(layer "F.Fab")
		)
		(fp_line
			(start 0.67945 -0.3048)
			(end 0.67945 0.3048)
			(stroke
				(width 0.1)
				(type default)
			)
			(layer "F.Fab")
		)
		(fp_line
			(start -0.67945 -0.305054)
			(end -0.12065 -0.305054)
			(stroke
				(width 0.1)
				(type default)
			)
			(layer "F.Fab")
		)
		(fp_line
			(start -0.12065 -0.305054)
			(end -0.12065 -0.2794)
			(stroke
				(width 0.1)
				(type default)
			)
			(layer "F.Fab")
		)
		(pad "1" smd circle
			(at -0.40005 0 270)
			(size 0 0)
			(layers "F.Cu" "F.Mask" "F.Paste")
			(net "P3V3_OCP_MODE_2")
		)
		(pad "2" smd circle
			(at 0.40005 0 270)
			(size 0 0)
			(layers "F.Cu" "F.Mask" "F.Paste")
			(net "GND")
		)
	)
)
